(kicad_pcb
	(version 20260206)
	(generator "pcbnew")
	(generator_version "10.0")
	(general
		(thickness 1.6)
		(legacy_teardrops no)
	)
	(paper "A4")
	(title_block
		(title "03242023_DA0F0TMBIJ0_F0T_Motherboard_J_brd_V01_OCP.brd")
		(comment 1 "Grand Teton / footprint 2856 of 6105 (J2), pads 225-291 of 291")
	)
	(layers
		(0 "F.Cu" signal "TOP")
		(4 "In1.Cu" signal "GND")
		(6 "In2.Cu" signal "IN1")
		(8 "In3.Cu" signal "GND1")
		(10 "In4.Cu" signal "IN2")
		(12 "In5.Cu" signal "GND2")
		(14 "In6.Cu" signal "IN3")
		(16 "In7.Cu" signal "GND3")
		(18 "In8.Cu" signal "VCC")
		(20 "In9.Cu" signal "VCC1")
		(22 "In10.Cu" signal "GND4")
		(24 "In11.Cu" signal "IN4")
		(26 "In12.Cu" signal "GND5")
		(28 "In13.Cu" signal "IN5")
		(30 "In14.Cu" signal "GND6")
		(32 "In15.Cu" signal "IN6")
		(34 "In16.Cu" signal "GND7")
		(2 "B.Cu" signal "BOTTOM")
		(9 "F.Adhes" user "F.Adhesive")
		(11 "B.Adhes" user "B.Adhesive")
		(13 "F.Paste" user "Package Geometry/Pastemask Top")
		(15 "B.Paste" user "Package Geometry/Pastemask Bottom")
		(5 "F.SilkS" user "Ref Des/Silkscreen Top")
		(7 "B.SilkS" user "Ref Des/Silkscreen Bottom")
		(1 "F.Mask" user "Board Geometry/Soldermask Top")
		(3 "B.Mask" user "Board Geometry/Soldermask Bottom")
		(17 "Dwgs.User" user "User.Drawings")
		(19 "Cmts.User" user "User.Comments")
		(21 "Eco1.User" user "User.Eco1")
		(23 "Eco2.User" user "User.Eco2")
		(25 "Edge.Cuts" user "Board Geometry/Outline")
		(27 "Margin" user)
		(31 "F.CrtYd" user "Package Geometry/Place Bound Top")
		(29 "B.CrtYd" user "Package Geometry/Place Bound Bottom")
		(35 "F.Fab" user "Ref Des/Assembly Top")
		(33 "B.Fab" user "Ref Des/Assembly Bottom")
	)
	(footprint ""
		(layer "F.Cu")
		(at 310.937148 -258.091686)
		(property "Reference" "J2"
			(at -3.683 -81.702148 0)
			(unlocked yes)
			(layer "F.SilkS")
			(effects
				(font
					(size 0.7874 0.5842)
					(thickness 0.1524)
				)
				(justify left)
			)
		)
		(property "Value" ""
			(at 0 0 0)
			(layer "F.Fab")
			(effects
				(font
					(size 1.27 1.27)
				)
			)
		)
		(duplicate_pad_numbers_are_jumpers no)
		(pad "225" smd rect
			(at 2.050034 9.774936 270)
			(size 0.519938 1.4986)
			(layers "F.Cu" "F.Mask" "F.Paste")
			(net "M_A_CPU0_SB_CA<5>")
		)
		(pad "226" smd rect
			(at 2.050034 10.625074 270)
			(size 0.519938 1.4986)
			(layers "F.Cu" "F.Mask" "F.Paste")
			(net "GND")
		)
		(pad "227" smd rect
			(at 2.050034 11.474958 270)
			(size 0.519938 1.4986)
			(layers "F.Cu" "F.Mask" "F.Paste")
			(net "M_A_CPU0_SB_PAR")
		)
		(pad "228" smd rect
			(at 2.050034 12.325096 270)
			(size 0.519938 1.4986)
			(layers "F.Cu" "F.Mask" "F.Paste")
			(net "GND")
		)
		(pad "229" smd rect
			(at 2.050034 13.17498 270)
			(size 0.519938 1.4986)
			(layers "F.Cu" "F.Mask" "F.Paste")
			(net "M_A_CPU0_SB_CS_N<3>")
		)
		(pad "230" smd rect
			(at 2.050034 14.025118 270)
			(size 0.519938 1.4986)
			(layers "F.Cu" "F.Mask" "F.Paste")
			(net "GND")
		)
		(pad "231" smd rect
			(at 2.050034 14.875002 270)
			(size 0.519938 1.4986)
			(layers "F.Cu" "F.Mask" "F.Paste")
			(net "TP_CHA_CPU0_DIMM2_FRU_5")
		)
		(pad "232" smd rect
			(at 2.050034 15.724886 270)
			(size 0.519938 1.4986)
			(layers "F.Cu" "F.Mask" "F.Paste")
			(net "TP_CHA_CPU0_DIMM2_FRU_6")
		)
		(pad "233" smd rect
			(at 2.050034 16.575024 270)
			(size 0.519938 1.4986)
			(layers "F.Cu" "F.Mask" "F.Paste")
			(net "GND")
		)
		(pad "234" smd rect
			(at 2.050034 17.424908 270)
			(size 0.519938 1.4986)
			(layers "F.Cu" "F.Mask" "F.Paste")
			(net "M_A_CPU0_SB_CB<6>")
		)
		(pad "235" smd rect
			(at 2.050034 18.275046 270)
			(size 0.519938 1.4986)
			(layers "F.Cu" "F.Mask" "F.Paste")
			(net "GND")
		)
		(pad "236" smd rect
			(at 2.050034 19.12493 270)
			(size 0.519938 1.4986)
			(layers "F.Cu" "F.Mask" "F.Paste")
			(net "M_A_CPU0_SB_CB<7>")
		)
		(pad "237" smd rect
			(at 2.050034 19.975068 270)
			(size 0.519938 1.4986)
			(layers "F.Cu" "F.Mask" "F.Paste")
			(net "GND")
		)
		(pad "238" smd rect
			(at 2.050034 20.824952 270)
			(size 0.519938 1.4986)
			(layers "F.Cu" "F.Mask" "F.Paste")
			(net "M_A_CPU0_SB_DQS_DN<4>")
		)
		(pad "239" smd rect
			(at 2.050034 21.67509 270)
			(size 0.519938 1.4986)
			(layers "F.Cu" "F.Mask" "F.Paste")
			(net "M_A_CPU0_SB_DQS_DP<4>")
		)
		(pad "240" smd rect
			(at 2.050034 22.524974 270)
			(size 0.519938 1.4986)
			(layers "F.Cu" "F.Mask" "F.Paste")
			(net "GND")
		)
		(pad "241" smd rect
			(at 2.050034 23.375112 270)
			(size 0.519938 1.4986)
			(layers "F.Cu" "F.Mask" "F.Paste")
			(net "M_A_CPU0_SB_CB<2>")
		)
		(pad "242" smd rect
			(at 2.050034 24.224996 270)
			(size 0.519938 1.4986)
			(layers "F.Cu" "F.Mask" "F.Paste")
			(net "GND")
		)
		(pad "243" smd rect
			(at 2.050034 25.07488 270)
			(size 0.519938 1.4986)
			(layers "F.Cu" "F.Mask" "F.Paste")
			(net "M_A_CPU0_SB_CB<3>")
		)
		(pad "244" smd rect
			(at 2.050034 25.925018 270)
			(size 0.519938 1.4986)
			(layers "F.Cu" "F.Mask" "F.Paste")
			(net "GND")
		)
		(pad "245" smd rect
			(at 2.050034 26.774902 270)
			(size 0.519938 1.4986)
			(layers "F.Cu" "F.Mask" "F.Paste")
			(net "M_A_CPU0_SB_DQ<2>")
		)
		(pad "246" smd rect
			(at 2.050034 27.62504 270)
			(size 0.519938 1.4986)
			(layers "F.Cu" "F.Mask" "F.Paste")
			(net "GND")
		)
		(pad "247" smd rect
			(at 2.050034 28.474924 270)
			(size 0.519938 1.4986)
			(layers "F.Cu" "F.Mask" "F.Paste")
			(net "M_A_CPU0_SB_DQ<3>")
		)
		(pad "248" smd rect
			(at 2.050034 29.325062 270)
			(size 0.519938 1.4986)
			(layers "F.Cu" "F.Mask" "F.Paste")
			(net "GND")
		)
		(pad "249" smd rect
			(at 2.050034 30.174946 270)
			(size 0.519938 1.4986)
			(layers "F.Cu" "F.Mask" "F.Paste")
			(net "M_A_CPU0_SB_DQS_DN<5>")
		)
		(pad "250" smd rect
			(at 2.050034 31.025084 270)
			(size 0.519938 1.4986)
			(layers "F.Cu" "F.Mask" "F.Paste")
			(net "M_A_CPU0_SB_DQS_DP<5>")
		)
		(pad "251" smd rect
			(at 2.050034 31.874968 270)
			(size 0.519938 1.4986)
			(layers "F.Cu" "F.Mask" "F.Paste")
			(net "GND")
		)
		(pad "252" smd rect
			(at 2.050034 32.725106 270)
			(size 0.519938 1.4986)
			(layers "F.Cu" "F.Mask" "F.Paste")
			(net "M_A_CPU0_SB_DQ<6>")
		)
		(pad "253" smd rect
			(at 2.050034 33.57499 270)
			(size 0.519938 1.4986)
			(layers "F.Cu" "F.Mask" "F.Paste")
			(net "GND")
		)
		(pad "254" smd rect
			(at 2.050034 34.425128 270)
			(size 0.519938 1.4986)
			(layers "F.Cu" "F.Mask" "F.Paste")
			(net "M_A_CPU0_SB_DQ<7>")
		)
		(pad "255" smd rect
			(at 2.050034 35.275012 270)
			(size 0.519938 1.4986)
			(layers "F.Cu" "F.Mask" "F.Paste")
			(net "GND")
		)
		(pad "256" smd rect
			(at 2.050034 36.124896 270)
			(size 0.519938 1.4986)
			(layers "F.Cu" "F.Mask" "F.Paste")
			(net "M_A_CPU0_SB_DQ<10>")
		)
		(pad "257" smd rect
			(at 2.050034 36.975034 270)
			(size 0.519938 1.4986)
			(layers "F.Cu" "F.Mask" "F.Paste")
			(net "GND")
		)
		(pad "258" smd rect
			(at 2.050034 37.824918 270)
			(size 0.519938 1.4986)
			(layers "F.Cu" "F.Mask" "F.Paste")
			(net "M_A_CPU0_SB_DQ<11>")
		)
		(pad "259" smd rect
			(at 2.050034 38.675056 270)
			(size 0.519938 1.4986)
			(layers "F.Cu" "F.Mask" "F.Paste")
			(net "GND")
		)
		(pad "260" smd rect
			(at 2.050034 39.52494 270)
			(size 0.519938 1.4986)
			(layers "F.Cu" "F.Mask" "F.Paste")
			(net "M_A_CPU0_SB_DQS_DN<6>")
		)
		(pad "261" smd rect
			(at 2.050034 40.375078 270)
			(size 0.519938 1.4986)
			(layers "F.Cu" "F.Mask" "F.Paste")
			(net "M_A_CPU0_SB_DQS_DP<6>")
		)
		(pad "262" smd rect
			(at 2.050034 41.224962 270)
			(size 0.519938 1.4986)
			(layers "F.Cu" "F.Mask" "F.Paste")
			(net "GND")
		)
		(pad "263" smd rect
			(at 2.050034 42.0751 270)
			(size 0.519938 1.4986)
			(layers "F.Cu" "F.Mask" "F.Paste")
			(net "M_A_CPU0_SB_DQ<14>")
		)
		(pad "264" smd rect
			(at 2.050034 42.924984 270)
			(size 0.519938 1.4986)
			(layers "F.Cu" "F.Mask" "F.Paste")
			(net "GND")
		)
		(pad "265" smd rect
			(at 2.050034 43.775122 270)
			(size 0.519938 1.4986)
			(layers "F.Cu" "F.Mask" "F.Paste")
			(net "M_A_CPU0_SB_DQ<15>")
		)
		(pad "266" smd rect
			(at 2.050034 44.625006 270)
			(size 0.519938 1.4986)
			(layers "F.Cu" "F.Mask" "F.Paste")
			(net "GND")
		)
		(pad "267" smd rect
			(at 2.050034 45.47489 270)
			(size 0.519938 1.4986)
			(layers "F.Cu" "F.Mask" "F.Paste")
			(net "M_A_CPU0_SB_DQ<18>")
		)
		(pad "268" smd rect
			(at 2.050034 46.325028 270)
			(size 0.519938 1.4986)
			(layers "F.Cu" "F.Mask" "F.Paste")
			(net "GND")
		)
		(pad "269" smd rect
			(at 2.050034 47.174912 270)
			(size 0.519938 1.4986)
			(layers "F.Cu" "F.Mask" "F.Paste")
			(net "M_A_CPU0_SB_DQ<19>")
		)
		(pad "270" smd rect
			(at 2.050034 48.02505 270)
			(size 0.519938 1.4986)
			(layers "F.Cu" "F.Mask" "F.Paste")
			(net "GND")
		)
		(pad "271" smd rect
			(at 2.050034 48.874934 270)
			(size 0.519938 1.4986)
			(layers "F.Cu" "F.Mask" "F.Paste")
			(net "M_A_CPU0_SB_DQS_DN<7>")
		)
		(pad "272" smd rect
			(at 2.050034 49.725072 270)
			(size 0.519938 1.4986)
			(layers "F.Cu" "F.Mask" "F.Paste")
			(net "M_A_CPU0_SB_DQS_DP<7>")
		)
		(pad "273" smd rect
			(at 2.050034 50.574956 270)
			(size 0.519938 1.4986)
			(layers "F.Cu" "F.Mask" "F.Paste")
			(net "GND")
		)
		(pad "274" smd rect
			(at 2.050034 51.425094 270)
			(size 0.519938 1.4986)
			(layers "F.Cu" "F.Mask" "F.Paste")
			(net "M_A_CPU0_SB_DQ<22>")
		)
		(pad "275" smd rect
			(at 2.050034 52.274978 270)
			(size 0.519938 1.4986)
			(layers "F.Cu" "F.Mask" "F.Paste")
			(net "GND")
		)
		(pad "276" smd rect
			(at 2.050034 53.125116 270)
			(size 0.519938 1.4986)
			(layers "F.Cu" "F.Mask" "F.Paste")
			(net "M_A_CPU0_SB_DQ<23>")
		)
		(pad "277" smd rect
			(at 2.050034 53.975 270)
			(size 0.519938 1.4986)
			(layers "F.Cu" "F.Mask" "F.Paste")
			(net "GND")
		)
		(pad "278" smd rect
			(at 2.050034 54.824884 270)
			(size 0.519938 1.4986)
			(layers "F.Cu" "F.Mask" "F.Paste")
			(net "M_A_CPU0_SB_DQ<26>")
		)
		(pad "279" smd rect
			(at 2.050034 55.675022 270)
			(size 0.519938 1.4986)
			(layers "F.Cu" "F.Mask" "F.Paste")
			(net "GND")
		)
		(pad "280" smd rect
			(at 2.050034 56.524906 270)
			(size 0.519938 1.4986)
			(layers "F.Cu" "F.Mask" "F.Paste")
			(net "M_A_CPU0_SB_DQ<27>")
		)
		(pad "281" smd rect
			(at 2.050034 57.375044 270)
			(size 0.519938 1.4986)
			(layers "F.Cu" "F.Mask" "F.Paste")
			(net "GND")
		)
		(pad "282" smd rect
			(at 2.050034 58.224928 270)
			(size 0.519938 1.4986)
			(layers "F.Cu" "F.Mask" "F.Paste")
			(net "M_A_CPU0_SB_DQS_DN<8>")
		)
		(pad "283" smd rect
			(at 2.050034 59.075066 270)
			(size 0.519938 1.4986)
			(layers "F.Cu" "F.Mask" "F.Paste")
			(net "M_A_CPU0_SB_DQS_DP<8>")
		)
		(pad "284" smd rect
			(at 2.050034 59.92495 270)
			(size 0.519938 1.4986)
			(layers "F.Cu" "F.Mask" "F.Paste")
			(net "GND")
		)
		(pad "285" smd rect
			(at 2.050034 60.775088 270)
			(size 0.519938 1.4986)
			(layers "F.Cu" "F.Mask" "F.Paste")
			(net "M_A_CPU0_SB_DQ<30>")
		)
		(pad "286" smd rect
			(at 2.050034 61.624972 270)
			(size 0.519938 1.4986)
			(layers "F.Cu" "F.Mask" "F.Paste")
			(net "GND")
		)
		(pad "287" smd rect
			(at 2.050034 62.47511 270)
			(size 0.519938 1.4986)
			(layers "F.Cu" "F.Mask" "F.Paste")
			(net "M_A_CPU0_SB_DQ<31>")
		)
		(pad "288" smd rect
			(at 2.050034 63.324994 270)
			(size 0.519938 1.4986)
			(layers "F.Cu" "F.Mask" "F.Paste")
			(net "GND")
		)
		(pad "G1" thru_hole oval
			(at 0 -68.97497)
			(size 2.8194 1.5748)
			(drill oval 2.4384 1.1938)
			(layers "*.Cu" "*.Mask")
			(remove_unused_layers no)
			(net "GND")
			(clearance 0.127)
			(thermal_gap 0.127)
		)
		(pad "G2" thru_hole oval
			(at 0 3.875024)
			(size 2.8194 1.5748)
			(drill oval 2.4384 1.1938)
			(layers "*.Cu" "*.Mask")
			(remove_unused_layers no)
			(net "GND")
			(clearance 0.127)
			(thermal_gap 0.127)
		)
		(pad "G3" thru_hole oval
			(at 0 68.97497)
			(size 2.8194 1.5748)
			(drill oval 2.4384 1.1938)
			(layers "*.Cu" "*.Mask")
			(remove_unused_layers no)
			(net "GND")
			(clearance 0.127)
			(thermal_gap 0.127)
		)
	)
)
